# S9S_MB_2U (Grand Teton) — schematic netlist excerpt (pin names and nets, part order shuffled) for the footprints in the layout excerpt that follows; sources: Cadence DE-HDL packaged netlist, KiCad conversion of 03242023_DA0F0TMBIJ0_F0T_Motherboard_J_brd_V01_OCP.brd

J2  SCONN288_ADR50017P087CC  SCONN288_ADR50017-P087CC IO  pkg DDR288S_1-1VXB  page 83
  VIN_BULK0  = P12V_S3_AUX_CPU0_NVDIMM
  RFU0  = TP_CHA_CPU0_DIMM2_FRU_0
  VIN_MGMT  = P3V3_AUX
  HSCL  = I3C_SPD_DDRABCD_CPU0_LVC1_SCL_1
  HSDA  = I3C_SPD_DDRABCD_CPU0_LVC1_SDA
  VSS0  = GND
  DQ0_A  = M_A_CPU0_SA_DQ<0>
  VSS1  = GND
  DQ1_A  = M_A_CPU0_SA_DQ<1>
  VSS2  = GND
  DQS0_A_T  = M_A_CPU0_SA_DQS_DP<0>
  DQS0_A_C  = M_A_CPU0_SA_DQS_DN<0>
  VSS3  = GND
  DQ4_A  = M_A_CPU0_SA_DQ<4>
  VSS4  = GND
  DQ5_A  = M_A_CPU0_SA_DQ<5>
  VSS5  = GND
  DQ8_A  = M_A_CPU0_SA_DQ<8>
  VSS6  = GND
  DQ9_A  = M_A_CPU0_SA_DQ<9>
  VSS7  = GND
  DQS1_A_T  = M_A_CPU0_SA_DQS_DP<1>
  DQS1_A_C  = M_A_CPU0_SA_DQS_DN<1>
  VSS8  = GND
  DQ12_A  = M_A_CPU0_SA_DQ<12>
  VSS9  = GND
  DQ13_A  = M_A_CPU0_SA_DQ<13>
  VSS10  = GND
  DQ16_A  = M_A_CPU0_SA_DQ<16>
  VSS11  = GND
  DQ17_A  = M_A_CPU0_SA_DQ<17>
  VSS12  = GND
  DQS2_A_T  = M_A_CPU0_SA_DQS_DP<2>
  DQS2_A_C  = M_A_CPU0_SA_DQS_DN<2>
  VSS13  = GND
  DQ20_A  = M_A_CPU0_SA_DQ<20>
  VSS14  = GND
  DQ21_A  = M_A_CPU0_SA_DQ<21>
  VSS15  = GND
  DQ24_A  = M_A_CPU0_SA_DQ<24>
  VSS16  = GND
  DQ25_A  = M_A_CPU0_SA_DQ<25>
  VSS17  = GND
  DQS3_A_T  = M_A_CPU0_SA_DQS_DP<3>
  DQS3_A_C  = M_A_CPU0_SA_DQS_DN<3>
  VSS18  = GND
  DQ28_A  = M_A_CPU0_SA_DQ<28>
  VSS19  = GND
  DQ29_A  = M_A_CPU0_SA_DQ<29>
  VSS20  = GND
  CB0_A  = M_A_CPU0_SA_CB<0>
  VSS21  = GND
  CB1_A  = M_A_CPU0_SA_CB<1>
  VSS22  = GND
  DQS4_A_T  = M_A_CPU0_SA_DQS_DP<4>
  DQS4_A_C  = M_A_CPU0_SA_DQS_DN<4>
  VSS23  = GND
  CB4_A  = M_A_CPU0_SA_CB<4>
  VSS24  = GND
  CB5_A  = M_A_CPU0_SA_CB<5>
  VSS25  = GND
  ALERT_N  = M_A_CPU0_ALERT_N
  VSS26  = GND
  CS0_A_N  = M_A_CPU0_SA_CS_N<2>
  VSS27  = GND
  CA0_A  = M_A_CPU0_SA_CA<0>
  VSS28  = GND
  CA2_A  = M_A_CPU0_SA_CA<2>
  VSS29  = GND
  CA4_A  = M_A_CPU0_SA_CA<4>
  VSS30  = GND
  CA6_A  = M_A_CPU0_SA_CA<6>
  VSS31  = GND
  PAR_A  = M_A_CPU0_SA_PAR
  VSS32  = GND
  CA0_B  = M_A_CPU0_SB_CA<0>
  VSS33  = GND
  CA2_B  = M_A_CPU0_SB_CA<2>
  VSS34  = GND
  CA4_B  = M_A_CPU0_SB_CA<4>
  VSS35  = GND
  CA6_B  = M_A_CPU0_SB_CA<6>
  VSS36  = GND
  CS0_B_N  = M_A_CPU0_SB_CS_N<2>
  VSS37  = GND
  \lbd||rsp_a_n\  = M_A_CPU0_SA_RSP<1>
  \lbs||rsp_b_n\  = M_A_CPU0_SB_RSP<1>
  VSS38  = GND
  CB4_B  = M_A_CPU0_SB_CB<4>
  VSS39  = GND
  CB5_B  = M_A_CPU0_SB_CB<5>
  VSS40  = GND
  \dqs9_b_t||tdqs9_b_t||dbi4_b_n\  = M_A_CPU0_SB_DQS_DP<9>
  \dqs9_b_c||tdqs9_b_c\  = M_A_CPU0_SB_DQS_DN<9>
  VSS41  = GND
  CB0_B  = M_A_CPU0_SB_CB<0>
  VSS42  = GND
  CB1_B  = M_A_CPU0_SB_CB<1>
  VSS43  = GND
  DQ0_B  = M_A_CPU0_SB_DQ<0>
  VSS44  = GND
  DQ1_B  = M_A_CPU0_SB_DQ<1>
  VSS45  = GND
  DQS0_B_T  = M_A_CPU0_SB_DQS_DP<0>
  DQS0_B_C  = M_A_CPU0_SB_DQS_DN<0>
  VSS46  = GND
  DQ4_B  = M_A_CPU0_SB_DQ<4>
  VSS47  = GND
  DQ5_B  = M_A_CPU0_SB_DQ<5>
  VSS48  = GND
  DQ8_B  = M_A_CPU0_SB_DQ<8>
  VSS49  = GND
  DQ9_B  = M_A_CPU0_SB_DQ<9>
  VSS50  = GND
  DQS1_B_T  = M_A_CPU0_SB_DQS_DP<1>
  DQS1_B_C  = M_A_CPU0_SB_DQS_DN<1>
  VSS51  = GND
  DQ12_B  = M_A_CPU0_SB_DQ<12>
  VSS52  = GND
  DQ13_B  = M_A_CPU0_SB_DQ<13>
  VSS53  = GND
  DQ16_B  = M_A_CPU0_SB_DQ<16>
  VSS54  = GND
  DQ17_B  = M_A_CPU0_SB_DQ<17>
  VSS55  = GND
  DQS2_B_T  = M_A_CPU0_SB_DQS_DP<2>
  DQS2_B_C  = M_A_CPU0_SB_DQS_DN<2>
  VSS56  = GND
  DQ20_B  = M_A_CPU0_SB_DQ<20>
  VSS57  = GND
  DQ21_B  = M_A_CPU0_SB_DQ<21>
  VSS58  = GND
  DQ24_B  = M_A_CPU0_SB_DQ<24>
  VSS59  = GND
  DQ25_B  = M_A_CPU0_SB_DQ<25>
  VSS60  = GND
  DQS3_B_T  = M_A_CPU0_SB_DQS_DP<3>
  DQS3_B_C  = M_A_CPU0_SB_DQS_DN<3>
  VSS61  = GND
  DQ28_B  = M_A_CPU0_SB_DQ<28>
  VSS62  = GND
  DQ29_B  = M_A_CPU0_SB_DQ<29>
  VSS63  = GND
  RFU1  = TP_CHA_CPU0_DIMM2_FRU_1
  VIN_BULK1  = P12V_S3_AUX_CPU0_NVDIMM
  VIN_BULK2  = P12V_S3_AUX_CPU0_NVDIMM
  \pwr_good||fail_n\  = PWRGD_CHA_CPU0_DIMM2
  HSA  = PD_CHA_CPU0_DIMM2_SAA
  RFU2  = TP_CHA_CPU0_DIMM2_FRU_2
  RFU3  = TP_CHA_CPU0_DIMM2_FRU_3
  VSS64  = GND
  DQ2_A  = M_A_CPU0_SA_DQ<2>
  VSS65  = GND
  DQ3_A  = M_A_CPU0_SA_DQ<3>
  VSS66  = GND
  \dqs5_a_c||tdqs5_a_c||dqs5_a_t||tdqs5_a_t\  = M_A_CPU0_SA_DQS_DN<5>
  \dqs5_a_t||tdqs5_a_t\  = M_A_CPU0_SA_DQS_DP<5>
  VSS67  = GND
  DQ6_A  = M_A_CPU0_SA_DQ<6>
  VSS68  = GND
  DQ7_A  = M_A_CPU0_SA_DQ<7>
  VSS69  = GND
  DQ10_A  = M_A_CPU0_SA_DQ<10>
  VSS70  = GND
  DQ11_A  = M_A_CPU0_SA_DQ<11>
  VSS71  = GND
  \dqs6_a_c||tdqs6_a_c||dqs6_a_t||tdqs6_a_t\  = M_A_CPU0_SA_DQS_DN<6>
  \dqs6_a_t||tdqs6_a_t\  = M_A_CPU0_SA_DQS_DP<6>
  VSS72  = GND
  DQ14_A  = M_A_CPU0_SA_DQ<14>
  VSS73  = GND
  DQ15_A  = M_A_CPU0_SA_DQ<15>
  VSS74  = GND
  DQ18_A  = M_A_CPU0_SA_DQ<18>
  VSS75  = GND
  DQ19_A  = M_A_CPU0_SA_DQ<19>
  VSS76  = GND
  \dqs7_a_c||tdqs7_a_c\  = M_A_CPU0_SA_DQS_DN<7>
  \dqs7_a_t||tdqs7_a_t\  = M_A_CPU0_SA_DQS_DP<7>
  VSS77  = GND
  DQ22_A  = M_A_CPU0_SA_DQ<22>
  VSS78  = GND
  DQ23_A  = M_A_CPU0_SA_DQ<23>
  VSS79  = GND
  DQ26_A  = M_A_CPU0_SA_DQ<26>
  VSS80  = GND
  DQ27_A  = M_A_CPU0_SA_DQ<27>
  VSS81  = GND
  \dqs8_a_c||tdqs8_a_c\  = M_A_CPU0_SA_DQS_DN<8>
  \dqs8_a_t||tdqs8_a_t\  = M_A_CPU0_SA_DQS_DP<8>
  VSS82  = GND
  DQ30_A  = M_A_CPU0_SA_DQ<30>
  VSS83  = GND
  DQ31_A  = M_A_CPU0_SA_DQ<31>
  VSS84  = GND
  CB2_A  = M_A_CPU0_SA_CB<2>
  VSS85  = GND
  CB3_A  = M_A_CPU0_SA_CB<3>
  VSS86  = GND
  \dqs9_a_c||tdqs9_a_c\  = M_A_CPU0_SA_DQS_DN<9>
  \dqs9_a_t||tdqs9_a_t\  = M_A_CPU0_SA_DQS_DP<9>
  VSS87  = GND
  CB6_A  = M_A_CPU0_SA_CB<6>
  VSS88  = GND
  CB7_A  = M_A_CPU0_SA_CB<7>
  VSS89  = GND
  RESET_N  = RST_M_AB_CPU0_FPGA_N
  VSS90  = GND
  CS1_A_N  = M_A_CPU0_SA_CS_N<3>
  VSS91  = GND
  CA1_A  = M_A_CPU0_SA_CA<1>
  VSS92  = GND
  CA3_A  = M_A_CPU0_SA_CA<3>
  VSS93  = GND
  CA5_A  = M_A_CPU0_SA_CA<5>
  VSS94  = GND
  CK_T  = M_A_CPU0_CLK_DP<1>
  CK_C  = M_A_CPU0_CLK_DN<1>
  VSS95  = GND
  RFU4  = TP_CHA_CPU0_DIMM2_FRU_4
  CA1_B  = M_A_CPU0_SB_CA<1>
  VSS96  = GND
  CA3_B  = M_A_CPU0_SB_CA<3>
  VSS97  = GND
  CA5_B  = M_A_CPU0_SB_CA<5>
  VSS98  = GND
  PAR_B  = M_A_CPU0_SB_PAR
  VSS99  = GND
  CS1_B_N  = M_A_CPU0_SB_CS_N<3>
  VSS100  = GND
  RFU5  = TP_CHA_CPU0_DIMM2_FRU_5
  RFU6  = TP_CHA_CPU0_DIMM2_FRU_6
  VSS101  = GND
  CB6_B  = M_A_CPU0_SB_CB<6>
  VSS102  = GND
  CB7_B  = M_A_CPU0_SB_CB<7>
  VSS103  = GND
  DQS4_B_C  = M_A_CPU0_SB_DQS_DN<4>
  DQS4_B_T  = M_A_CPU0_SB_DQS_DP<4>
  VSS104  = GND
  CB2_B  = M_A_CPU0_SB_CB<2>
  VSS105  = GND
  CB3_B  = M_A_CPU0_SB_CB<3>
  VSS106  = GND
  DQ2_B  = M_A_CPU0_SB_DQ<2>
  VSS107  = GND
  DQ3_B  = M_A_CPU0_SB_DQ<3>
  VSS108  = GND
  \dqs5_b_c||tdqs5_b_c\  = M_A_CPU0_SB_DQS_DN<5>
  \dqs5_b_t||tdqs5_b_t\  = M_A_CPU0_SB_DQS_DP<5>
  VSS109  = GND
  DQ6_B  = M_A_CPU0_SB_DQ<6>
  VSS110  = GND
  DQ7_B  = M_A_CPU0_SB_DQ<7>
  VSS111  = GND
  DQ10_B  = M_A_CPU0_SB_DQ<10>
  VSS112  = GND
  DQ11_B  = M_A_CPU0_SB_DQ<11>
  VSS113  = GND
  \dqs6_b_c||tdqs6_b_c\  = M_A_CPU0_SB_DQS_DN<6>
  \dqs6_b_t||tdqs6_b_t\  = M_A_CPU0_SB_DQS_DP<6>
  VSS114  = GND
  DQ14_B  = M_A_CPU0_SB_DQ<14>
  VSS115  = GND
  DQ15_B  = M_A_CPU0_SB_DQ<15>
  VSS116  = GND
  DQ18_B  = M_A_CPU0_SB_DQ<18>
  VSS117  = GND
  DQ19_B  = M_A_CPU0_SB_DQ<19>
  VSS118  = GND
  \dqs7_b_c||tdqs7_b_c\  = M_A_CPU0_SB_DQS_DN<7>
  \dqs7_b_t||tdqs7_b_t\  = M_A_CPU0_SB_DQS_DP<7>
  VSS119  = GND
  DQ22_B  = M_A_CPU0_SB_DQ<22>
  VSS120  = GND
  DQ23_B  = M_A_CPU0_SB_DQ<23>
  VSS121  = GND
  DQ26_B  = M_A_CPU0_SB_DQ<26>
  VSS122  = GND
  DQ27_B  = M_A_CPU0_SB_DQ<27>
  VSS123  = GND
  \dqs8_b_c||tdqs8_b_c\  = M_A_CPU0_SB_DQS_DN<8>
  \dqs8_b_t||tdqs8_b_t\  = M_A_CPU0_SB_DQS_DP<8>
  VSS124  = GND
  DQ30_B  = M_A_CPU0_SB_DQ<30>
  VSS125  = GND
  DQ31_B  = M_A_CPU0_SB_DQ<31>
  VSS126  = GND
  G1  = GND
  G2  = GND
  G3  = GND

(kicad_pcb
	(version 20260206)
	(generator "pcbnew")
	(generator_version "10.0")
	(general
		(thickness 1.6)
		(legacy_teardrops no)
	)
	(paper "A4")
	(title_block
		(title "03242023_DA0F0TMBIJ0_F0T_Motherboard_J_brd_V01_OCP.brd")
		(comment 1 "Grand Teton / footprint 2856 of 6105 (J2), pads 138-182 of 291")
	)
	(layers
		(0 "F.Cu" signal "TOP")
		(4 "In1.Cu" signal "GND")
		(6 "In2.Cu" signal "IN1")
		(8 "In3.Cu" signal "GND1")
		(10 "In4.Cu" signal "IN2")
		(12 "In5.Cu" signal "GND2")
		(14 "In6.Cu" signal "IN3")
		(16 "In7.Cu" signal "GND3")
		(18 "In8.Cu" signal "VCC")
		(20 "In9.Cu" signal "VCC1")
		(22 "In10.Cu" signal "GND4")
		(24 "In11.Cu" signal "IN4")
		(26 "In12.Cu" signal "GND5")
		(28 "In13.Cu" signal "IN5")
		(30 "In14.Cu" signal "GND6")
		(32 "In15.Cu" signal "IN6")
		(34 "In16.Cu" signal "GND7")
		(2 "B.Cu" signal "BOTTOM")
		(9 "F.Adhes" user "F.Adhesive")
		(11 "B.Adhes" user "B.Adhesive")
		(13 "F.Paste" user "Package Geometry/Pastemask Top")
		(15 "B.Paste" user "Package Geometry/Pastemask Bottom")
		(5 "F.SilkS" user "Ref Des/Silkscreen Top")
		(7 "B.SilkS" user "Ref Des/Silkscreen Bottom")
		(1 "F.Mask" user "Board Geometry/Soldermask Top")
		(3 "B.Mask" user "Board Geometry/Soldermask Bottom")
		(17 "Dwgs.User" user "User.Drawings")
		(19 "Cmts.User" user "User.Comments")
		(21 "Eco1.User" user "User.Eco1")
		(23 "Eco2.User" user "User.Eco2")
		(25 "Edge.Cuts" user "Board Geometry/Outline")
		(27 "Margin" user)
		(31 "F.CrtYd" user "Package Geometry/Place Bound Top")
		(29 "B.CrtYd" user "Package Geometry/Place Bound Bottom")
		(35 "F.Fab" user "Ref Des/Assembly Top")
		(33 "B.Fab" user "Ref Des/Assembly Bottom")
	)
	(footprint ""
		(layer "F.Cu")
		(at 310.937148 -258.091686)
		(property "Reference" "J2"
			(at -3.683 -81.702148 0)
			(unlocked yes)
			(layer "F.SilkS")
			(effects
				(font
					(size 0.7874 0.5842)
					(thickness 0.1524)
				)
				(justify left)
			)
		)
		(property "Value" ""
			(at 0 0 0)
			(layer "F.Fab")
			(effects
				(font
					(size 1.27 1.27)
				)
			)
		)
		(duplicate_pad_numbers_are_jumpers no)
		(pad "138" smd rect
			(at -2.050034 58.224928 270)
			(size 0.519938 1.4986)
			(layers "F.Cu" "F.Mask" "F.Paste")
			(net "M_A_CPU0_SB_DQS_DN<3>")
		)
		(pad "139" smd rect
			(at -2.050034 59.075066 270)
			(size 0.519938 1.4986)
			(layers "F.Cu" "F.Mask" "F.Paste")
			(net "GND")
		)
		(pad "140" smd rect
			(at -2.050034 59.92495 270)
			(size 0.519938 1.4986)
			(layers "F.Cu" "F.Mask" "F.Paste")
			(net "M_A_CPU0_SB_DQ<28>")
		)
		(pad "141" smd rect
			(at -2.050034 60.775088 270)
			(size 0.519938 1.4986)
			(layers "F.Cu" "F.Mask" "F.Paste")
			(net "GND")
		)
		(pad "142" smd rect
			(at -2.050034 61.624972 270)
			(size 0.519938 1.4986)
			(layers "F.Cu" "F.Mask" "F.Paste")
			(net "M_A_CPU0_SB_DQ<29>")
		)
		(pad "143" smd rect
			(at -2.050034 62.47511 270)
			(size 0.519938 1.4986)
			(layers "F.Cu" "F.Mask" "F.Paste")
			(net "GND")
		)
		(pad "144" smd rect
			(at -2.050034 63.324994 270)
			(size 0.519938 1.4986)
			(layers "F.Cu" "F.Mask" "F.Paste")
			(net "TP_CHA_CPU0_DIMM2_FRU_1")
		)
		(pad "145" smd rect
			(at 2.050034 -63.324994 270)
			(size 0.519938 1.4986)
			(layers "F.Cu" "F.Mask" "F.Paste")
			(net "P12V_S3_AUX_CPU0_NVDIMM")
		)
		(pad "146" smd rect
			(at 2.050034 -62.47511 270)
			(size 0.519938 1.4986)
			(layers "F.Cu" "F.Mask" "F.Paste")
			(net "P12V_S3_AUX_CPU0_NVDIMM")
		)
		(pad "147" smd rect
			(at 2.050034 -61.624972 270)
			(size 0.519938 1.4986)
			(layers "F.Cu" "F.Mask" "F.Paste")
			(net "PWRGD_CHA_CPU0_DIMM2")
		)
		(pad "148" smd rect
			(at 2.050034 -60.775088 270)
			(size 0.519938 1.4986)
			(layers "F.Cu" "F.Mask" "F.Paste")
			(net "PD_CHA_CPU0_DIMM2_SAA")
		)
		(pad "149" smd rect
			(at 2.050034 -59.92495 270)
			(size 0.519938 1.4986)
			(layers "F.Cu" "F.Mask" "F.Paste")
			(net "TP_CHA_CPU0_DIMM2_FRU_2")
		)
		(pad "150" smd rect
			(at 2.050034 -59.075066 270)
			(size 0.519938 1.4986)
			(layers "F.Cu" "F.Mask" "F.Paste")
			(net "TP_CHA_CPU0_DIMM2_FRU_3")
		)
		(pad "151" smd rect
			(at 2.050034 -58.224928 270)
			(size 0.519938 1.4986)
			(layers "F.Cu" "F.Mask" "F.Paste")
			(net "GND")
		)
		(pad "152" smd rect
			(at 2.050034 -57.375044 270)
			(size 0.519938 1.4986)
			(layers "F.Cu" "F.Mask" "F.Paste")
			(net "M_A_CPU0_SA_DQ<2>")
		)
		(pad "153" smd rect
			(at 2.050034 -56.524906 270)
			(size 0.519938 1.4986)
			(layers "F.Cu" "F.Mask" "F.Paste")
			(net "GND")
		)
		(pad "154" smd rect
			(at 2.050034 -55.675022 270)
			(size 0.519938 1.4986)
			(layers "F.Cu" "F.Mask" "F.Paste")
			(net "M_A_CPU0_SA_DQ<3>")
		)
		(pad "155" smd rect
			(at 2.050034 -54.824884 270)
			(size 0.519938 1.4986)
			(layers "F.Cu" "F.Mask" "F.Paste")
			(net "GND")
		)
		(pad "156" smd rect
			(at 2.050034 -53.975 270)
			(size 0.519938 1.4986)
			(layers "F.Cu" "F.Mask" "F.Paste")
			(net "M_A_CPU0_SA_DQS_DN<5>")
		)
		(pad "157" smd rect
			(at 2.050034 -53.125116 270)
			(size 0.519938 1.4986)
			(layers "F.Cu" "F.Mask" "F.Paste")
			(net "M_A_CPU0_SA_DQS_DP<5>")
		)
		(pad "158" smd rect
			(at 2.050034 -52.274978 270)
			(size 0.519938 1.4986)
			(layers "F.Cu" "F.Mask" "F.Paste")
			(net "GND")
		)
		(pad "159" smd rect
			(at 2.050034 -51.425094 270)
			(size 0.519938 1.4986)
			(layers "F.Cu" "F.Mask" "F.Paste")
			(net "M_A_CPU0_SA_DQ<6>")
		)
		(pad "160" smd rect
			(at 2.050034 -50.574956 270)
			(size 0.519938 1.4986)
			(layers "F.Cu" "F.Mask" "F.Paste")
			(net "GND")
		)
		(pad "161" smd rect
			(at 2.050034 -49.725072 270)
			(size 0.519938 1.4986)
			(layers "F.Cu" "F.Mask" "F.Paste")
			(net "M_A_CPU0_SA_DQ<7>")
		)
		(pad "162" smd rect
			(at 2.050034 -48.874934 270)
			(size 0.519938 1.4986)
			(layers "F.Cu" "F.Mask" "F.Paste")
			(net "GND")
		)
		(pad "163" smd rect
			(at 2.050034 -48.02505 270)
			(size 0.519938 1.4986)
			(layers "F.Cu" "F.Mask" "F.Paste")
			(net "M_A_CPU0_SA_DQ<10>")
		)
		(pad "164" smd rect
			(at 2.050034 -47.174912 270)
			(size 0.519938 1.4986)
			(layers "F.Cu" "F.Mask" "F.Paste")
			(net "GND")
		)
		(pad "165" smd rect
			(at 2.050034 -46.325028 270)
			(size 0.519938 1.4986)
			(layers "F.Cu" "F.Mask" "F.Paste")
			(net "M_A_CPU0_SA_DQ<11>")
		)
		(pad "166" smd rect
			(at 2.050034 -45.47489 270)
			(size 0.519938 1.4986)
			(layers "F.Cu" "F.Mask" "F.Paste")
			(net "GND")
		)
		(pad "167" smd rect
			(at 2.050034 -44.625006 270)
			(size 0.519938 1.4986)
			(layers "F.Cu" "F.Mask" "F.Paste")
			(net "M_A_CPU0_SA_DQS_DN<6>")
		)
		(pad "168" smd rect
			(at 2.050034 -43.775122 270)
			(size 0.519938 1.4986)
			(layers "F.Cu" "F.Mask" "F.Paste")
			(net "M_A_CPU0_SA_DQS_DP<6>")
		)
		(pad "169" smd rect
			(at 2.050034 -42.924984 270)
			(size 0.519938 1.4986)
			(layers "F.Cu" "F.Mask" "F.Paste")
			(net "GND")
		)
		(pad "170" smd rect
			(at 2.050034 -42.0751 270)
			(size 0.519938 1.4986)
			(layers "F.Cu" "F.Mask" "F.Paste")
			(net "M_A_CPU0_SA_DQ<14>")
		)
		(pad "171" smd rect
			(at 2.050034 -41.224962 270)
			(size 0.519938 1.4986)
			(layers "F.Cu" "F.Mask" "F.Paste")
			(net "GND")
		)
		(pad "172" smd rect
			(at 2.050034 -40.375078 270)
			(size 0.519938 1.4986)
			(layers "F.Cu" "F.Mask" "F.Paste")
			(net "M_A_CPU0_SA_DQ<15>")
		)
		(pad "173" smd rect
			(at 2.050034 -39.52494 270)
			(size 0.519938 1.4986)
			(layers "F.Cu" "F.Mask" "F.Paste")
			(net "GND")
		)
		(pad "174" smd rect
			(at 2.050034 -38.675056 270)
			(size 0.519938 1.4986)
			(layers "F.Cu" "F.Mask" "F.Paste")
			(net "M_A_CPU0_SA_DQ<18>")
		)
		(pad "175" smd rect
			(at 2.050034 -37.824918 270)
			(size 0.519938 1.4986)
			(layers "F.Cu" "F.Mask" "F.Paste")
			(net "GND")
		)
		(pad "176" smd rect
			(at 2.050034 -36.975034 270)
			(size 0.519938 1.4986)
			(layers "F.Cu" "F.Mask" "F.Paste")
			(net "M_A_CPU0_SA_DQ<19>")
		)
		(pad "177" smd rect
			(at 2.050034 -36.124896 270)
			(size 0.519938 1.4986)
			(layers "F.Cu" "F.Mask" "F.Paste")
			(net "GND")
		)
		(pad "178" smd rect
			(at 2.050034 -35.275012 270)
			(size 0.519938 1.4986)
			(layers "F.Cu" "F.Mask" "F.Paste")
			(net "M_A_CPU0_SA_DQS_DN<7>")
		)
		(pad "179" smd rect
			(at 2.050034 -34.425128 270)
			(size 0.519938 1.4986)
			(layers "F.Cu" "F.Mask" "F.Paste")
			(net "M_A_CPU0_SA_DQS_DP<7>")
		)
		(pad "180" smd rect
			(at 2.050034 -33.57499 270)
			(size 0.519938 1.4986)
			(layers "F.Cu" "F.Mask" "F.Paste")
			(net "GND")
		)
		(pad "181" smd rect
			(at 2.050034 -32.725106 270)
			(size 0.519938 1.4986)
			(layers "F.Cu" "F.Mask" "F.Paste")
			(net "M_A_CPU0_SA_DQ<22>")
		)
		(pad "182" smd rect
			(at 2.050034 -31.874968 270)
			(size 0.519938 1.4986)
			(layers "F.Cu" "F.Mask" "F.Paste")
			(net "GND")
		)
	)
)
